FILE_TYPE = CONNECTIVITY;
{Allegro Design Entry HDL 17.2-2016 S067 (3860444) 4/26/2020}
"PAGE_NUMBER" = 525;
0"NC";
1"UN$525$ISL80101IRAJZDFN10$I29$SENSE";
2"XP5R0V_FT4232\g";
3"SG\g";
4"XP3R3V_FT4232\g";
5"SG\g";
6"SG\g";
7"SG\g";
8"SG\g";
9"SG\g";
10"SG\g";
11"XP3R3V_FPGA\g";
12"XP5R0V\g";
13"UN$525$CAPACITOR$I7$1";
14"UN$525$CAPACITOR$I18$1";
15"UN$525$CAPACITOR$I14$1";
16"UN$525$CAPACITOR$I16$1";
17"XP3R3V_FT_PG";
%"FERRITEBEAD"
"1","(-300,3400)","0","passive","I10";
;
PACKAGE"0603"
VALUE"26OHM"
TOLERANCE"25%"
CLS_PN"G191-10101-01"
CDS_LMAN_SYM_OUTLINE"0,0,200,-100"
CDS_LIB"passive"
$LOCATION"L23"
CDS_LOCATION"L23"
$SEC"1"
CDS_SEC"1";
"2"
$PN"2"16;
"1"
$PN"1"13;
%"DIODE_2F"
"1","(-1600,3350)","0","discrete","I102";
;
CLS_PN"G122-10186-01"
CDS_LMAN_SYM_OUTLINE"-50,100,50,-100"
CDS_LIB"discrete"
$LOCATION"CR1"
CDS_LOCATION"CR1"
$SEC"1"
CDS_SEC"1";
"C"
$PN"C"13;
"A"
$PN"A"12;
%"DIODE_2F"
"1","(-1600,3200)","0","discrete","I104";
;
NO_ASSY"TRUE"
CLS_PN"G122-10186-01"
CDS_LMAN_SYM_OUTLINE"-50,100,50,-100"
CDS_LIB"discrete"
$LOCATION"CR2"
CDS_LOCATION"CR2"
$SEC"1"
CDS_SEC"1";
"C"
$PN"C"13;
"A"
$PN"A"2;
%"VCC"
"1","(-2350,3650)","0","cls","I105";
;
HDL_POWER"XP5R0V"
VOLTAGE"5.0"
CDS_LMAN_SYM_OUTLINE"-250,250,250,-250"
CDS_LIB"cls"
BODY_TYPE"PLUMBING";
"$PIN0"12;
%"VCC"
"1","(5150,3950)","0","cls","I107";
;
VOLTAGE"3.3V"
HDL_POWER"XP3R3V_FPGA"
BODY_TYPE"PLUMBING"
CDS_LMAN_SYM_OUTLINE"-250,250,250,-250"
CDS_LIB"cls";
"$PIN0"11;
%"FERRITEBEAD"
"1","(5700,3750)","0","passive","I108";
;
NO_ASSY"TRUE"
PACKAGE"0603"
VALUE"120OHM"
CDS_LIB"passive"
CDS_LMAN_SYM_OUTLINE"0,0,200,-100"
TOLERANCE"25%"
CLS_PN"G191-10100-01"
$LOCATION"L24"
CDS_LOCATION"L24"
$SEC"1"
CDS_SEC"1";
"2"
$PN"2"4;
"1"
$PN"1"11;
%"GND_SG"
"1","(250,1300)","0","cls","I11";
;
HDL_POWER"SG"
CDS_LMAN_SYM_OUTLINE"0,0,100,-50"
CDS_LIB"cls"
BODY_TYPE"PLUMBING";
"SGND"10;
%"RESISTOR"
"2","(300,1950)","0","passive","I13";
;
VALUE"10KOHM"
PACKAGE"0402"
CDS_LMAN_SYM_OUTLINE"-50,50,50,-100"
CDS_LIB"passive"
TOLERANCE"1%"
CLS_PN"G155-11002-01"
$LOCATION"R488"
CDS_LOCATION"R488"
$SEC"1"
CDS_SEC"1";
"1"
$PN"1"15;
"2"
$PN"2"10;
%"CAPACITOR"
"2","(850,1950)","0","passive","I14";
;
PACKAGE"0402"
VOLTAGE"25V"
VALUE"0.1UF"
TOLERANCE"10%"
CLS_PN"G105-0B104-EK"
CDS_LMAN_SYM_OUTLINE"-50,0,50,-50"
CDS_LIB"passive"
$LOCATION"C302"
CDS_LOCATION"C302"
$SEC"1"
CDS_SEC"1";
"2"
$PN"2"10;
"1"
$PN"1"15;
%"CAPACITOR"
"2","(800,3050)","0","passive","I16";
;
VOLTAGE"25V"
VALUE"10UF"
PACKAGE"0805"
CDS_LIB"passive"
CDS_LMAN_SYM_OUTLINE"-50,0,50,-50"
CLS_PN"G107-0F106-EM"
TOLERANCE"20%"
$LOCATION"C300"
CDS_LOCATION"C300"
$SEC"1"
CDS_SEC"1";
"2"
$PN"2"9;
"1"
$PN"1"16;
%"GND_SG"
"1","(1300,1450)","0","cls","I17";
;
VOLTAGE"0"
HDL_POWER"SG"
CDS_LIB"cls"
CDS_LMAN_SYM_OUTLINE"0,0,100,-50"
BODY_TYPE"PLUMBING";
"SGND"3;
%"CAPACITOR"
"2","(1350,1850)","0","passive","I18";
;
VALUE"0.01UF"
VOLTAGE"25V"
PACKAGE"0201"
CDS_LIB"passive"
CDS_LMAN_SYM_OUTLINE"-50,0,50,-50"
CLS_PN"G104-0B103-EK"
TOLERANCE"10%"
$LOCATION"C307"
CDS_LOCATION"C307"
$SEC"1"
CDS_SEC"1";
"2"
$PN"2"3;
"1"
$PN"1"14;
%"GND_SG"
"1","(1200,2600)","0","cls","I19";
;
HDL_POWER"SG"
VOLTAGE"0"
CDS_LIB"cls"
CDS_LMAN_SYM_OUTLINE"0,0,100,-50"
BODY_TYPE"PLUMBING";
"SGND"9;
%"CAPACITOR"
"2","(1250,3050)","0","passive","I20";
;
PACKAGE"0402"
VALUE"0.1UF"
VOLTAGE"25V"
CDS_LIB"passive"
CDS_LMAN_SYM_OUTLINE"-50,0,50,-50"
TOLERANCE"10%"
CLS_PN"G105-0B104-EK"
$LOCATION"C304"
CDS_LOCATION"C304"
$SEC"1"
CDS_SEC"1";
"2"
$PN"2"9;
"1"
$PN"1"16;
%"ISL80101IRAJZ_DFN10"
"1","(2150,2950)","0","analog","I29";
;
PART_NUMBER"ISL80101IRAJZ-T"
CLS_PN"G222-10136-01"
CDS_LIB"analog"
CDS_LMAN_SYM_OUTLINE"0,0,900,-1000"
$LOCATION"U41"
CDS_LOCATION"U41"
$SEC"1"
CDS_SEC"1";
"THRM_PAD"
$PN"11"8;
"VIN_2"
$PN"10"16;
"VIN_1"
$PN"9"16;
"NC"
$PN"8"0;
"ENABLE"
$PN"7"15;
"SS"
$PN"6"14;
"GND"
$PN"5"8;
"PG"
$PN"4"17;
"SENSE/ADJ"
$PN"3"1;
"VOUT_2"
$PN"2"4;
"VOUT_1"
$PN"1"4;
%"GND_SG"
"1","(3400,1350)","0","cls","I30";
;
VOLTAGE"0"
HDL_POWER"SG"
BODY_TYPE"PLUMBING"
CDS_LMAN_SYM_OUTLINE"0,0,100,-50"
CDS_LIB"cls";
"SGND"8;
%"GND_SG"
"1","(5450,1550)","0","cls","I35";
;
HDL_POWER"SG"
BODY_TYPE"PLUMBING"
CDS_LMAN_SYM_OUTLINE"0,0,100,-50"
CDS_LIB"cls";
"SGND"7;
%"GND_SG"
"1","(6700,2300)","0","cls","I55";
;
HDL_POWER"SG"
BODY_TYPE"PLUMBING"
CDS_LMAN_SYM_OUTLINE"0,0,100,-50"
CDS_LIB"cls";
"SGND"6;
%"CAPACITOR"
"2","(6750,2950)","0","passive","I56";
;
VOLTAGE"25V"
VALUE"0.1UF"
PACKAGE"0805"
CLS_PN"G105-0B104-EK"
TOLERANCE"10%"
CDS_LMAN_SYM_OUTLINE"-50,0,50,-50"
CDS_LIB"passive"
$LOCATION"C309"
CDS_LOCATION"C309"
$SEC"1"
CDS_SEC"1";
"2"
$PN"2"6;
"1"
$PN"1"4;
%"GND_SG"
"1","(-700,2700)","0","cls","I6";
;
HDL_POWER"SG"
CDS_LIB"cls"
CDS_LMAN_SYM_OUTLINE"0,0,100,-50"
BODY_TYPE"PLUMBING";
"SGND"5;
%"CAPACITOR"
"2","(6150,2950)","0","passive","I64";
;
VALUE"10UF"
VOLTAGE"25V"
PACKAGE"0805"
TOLERANCE"20%"
CLS_PN"G107-0F106-EM"
CDS_LMAN_SYM_OUTLINE"-50,0,50,-50"
CDS_LIB"passive"
$LOCATION"C308"
CDS_LOCATION"C308"
$SEC"1"
CDS_SEC"1";
"2"
$PN"2"6;
"1"
$PN"1"4;
%"RESISTOR"
"2","(300,2900)","0","passive","I65";
;
PACKAGE"0402"
VALUE"4.7KOHM"
CDS_LIB"passive"
CDS_LMAN_SYM_OUTLINE"-50,50,50,-100"
CLS_PN"G155-14701-01"
TOLERANCE"1%"
$LOCATION"R487"
CDS_LOCATION"R487"
$SEC"1"
CDS_SEC"1";
"1"
$PN"1"16;
"2"
$PN"2"15;
%"RESISTOR"
"2","(5500,2950)","0","passive","I66";
;
VALUE"10KOHM"
PACKAGE"0402"
CDS_LIB"passive"
CDS_LMAN_SYM_OUTLINE"-50,50,50,-100"
CLS_PN"G155-11002-01"
TOLERANCE"1%"
$LOCATION"R490"
CDS_LOCATION"R490"
$SEC"1"
CDS_SEC"1";
"1"
$PN"1"4;
"2"
$PN"2"1;
%"RESISTOR"
"2","(5500,2250)","0","passive","I67";
;
VALUE"3.24KOHM"
PACKAGE"0402"
CDS_LIB"passive"
CDS_LMAN_SYM_OUTLINE"-50,50,50,-100"
TOLERANCE"1%"
CLS_PN"G155-03241-01"
$LOCATION"R491"
CDS_LOCATION"R491"
$SEC"1"
CDS_SEC"1";
"1"
$PN"1"1;
"2"
$PN"2"7;
%"RESISTOR"
"2","(4900,2250)","0","passive","I68";
;
PACKAGE"0402"
VALUE"3.92KOHM"
CDS_LIB"passive"
CDS_LMAN_SYM_OUTLINE"-50,50,50,-100"
TOLERANCE"1%"
CLS_PN"G155-03921-01"
$LOCATION"R489"
CDS_LOCATION"R489"
$SEC"1"
CDS_SEC"1";
"1"
$PN"1"1;
"2"
$PN"2"7;
%"VCC"
"1","(6700,3950)","0","cls","I69";
;
VOLTAGE"3.3V"
HDL_POWER"XP3R3V_FT4232"
CDS_LIB"cls"
CDS_LMAN_SYM_OUTLINE"-250,250,250,-250"
BODY_TYPE"PLUMBING";
"$PIN0"4;
%"CAPACITOR"
"2","(-1100,3050)","0","passive","I7";
;
VOLTAGE"10V"
PACKAGE"0805"
VALUE"22UF"
CDS_LIB"passive"
CDS_LMAN_SYM_OUTLINE"-50,0,50,-50"
TOLERANCE"20%"
CLS_PN"G107-0F226-CM"
$LOCATION"C284"
CDS_LOCATION"C284"
$SEC"1"
CDS_SEC"1";
"2"
$PN"2"5;
"1"
$PN"1"13;
%"CAPACITOR"
"2","(-650,3050)","0","passive","I8";
;
PACKAGE"0402"
VOLTAGE"25V"
VALUE"0.1UF"
CDS_LIB"passive"
CDS_LMAN_SYM_OUTLINE"-50,0,50,-50"
TOLERANCE"10%"
CLS_PN"G105-0B104-EK"
MATERIAL"X7R"
$LOCATION"C298"
CDS_LOCATION"C298"
$SEC"1"
CDS_SEC"1";
"2"
$PN"2"5;
"1"
$PN"1"13;
%"VCC"
"1","(-2900,3650)","0","cls","I9";
;
HDL_POWER"XP5R0V_FT4232"
VOLTAGE"5V"
BODY_TYPE"PLUMBING"
CDS_LMAN_SYM_OUTLINE"-250,250,250,-250"
CDS_LIB"cls";
"$PIN0"2;
END.
